(kicad_pcb
	(version 20260206)
	(generator "pcbnew")
	(generator_version "10.0")
	(general
		(thickness 1.6)
		(legacy_teardrops no)
	)
	(paper "A4")
	(title_block
		(title "pdpb — Lightning_PDPB_BRD.brd")
		(comment 1 "Lightning (Wiwynn / Facebook NVMe JBOF) / footprints 718-724 of 1140")
	)
	(layers
		(0 "F.Cu" signal "TOP")
		(4 "In1.Cu" signal "L2GND")
		(6 "In2.Cu" signal "L3")
		(8 "In3.Cu" signal "L4VCC")
		(10 "In4.Cu" signal "L5VCC")
		(12 "In5.Cu" signal "L6")
		(14 "In6.Cu" signal "L7GND")
		(2 "B.Cu" signal "BOTTOM")
		(9 "F.Adhes" user "F.Adhesive")
		(11 "B.Adhes" user "B.Adhesive")
		(13 "F.Paste" user "Package Geometry/Pastemask Top")
		(15 "B.Paste" user "Package Geometry/Pastemask Bottom")
		(5 "F.SilkS" user "Ref Des/Silkscreen Top")
		(7 "B.SilkS" user "Ref Des/Silkscreen Bottom")
		(1 "F.Mask" user "Board Geometry/Soldermask Top")
		(3 "B.Mask" user "Board Geometry/Soldermask Bottom")
		(17 "Dwgs.User" user "User.Drawings")
		(19 "Cmts.User" user "User.Comments")
		(21 "Eco1.User" user "User.Eco1")
		(23 "Eco2.User" user "User.Eco2")
		(25 "Edge.Cuts" user "Board Geometry/Outline")
		(27 "Margin" user)
		(31 "F.CrtYd" user "Package Geometry/Place Bound Top")
		(29 "B.CrtYd" user "Package Geometry/Place Bound Bottom")
		(35 "F.Fab" user "Ref Des/Assembly Top")
		(33 "B.Fab" user "Ref Des/Assembly Bottom")
	)
	(footprint ""
		(layer "F.Cu")
		(at 217.043 -288.798 -90)
		(property "Reference" "R392"
			(at 0 0 270)
			(layer "F.SilkS")
			(hide yes)
			(effects
				(font
					(size 1.27 1.27)
				)
			)
		)
		(property "Value" "0R2J-2-GP"
			(at 0.064008 -3.993896 270)
			(unlocked yes)
			(layer "F.Fab")
			(hide yes)
			(effects
				(font
					(size 1.016 1.016)
					(thickness 0.1524)
				)
			)
		)
		(property "Device Type" "R402H16"
			(at 0.064008 -5.517896 270)
			(unlocked yes)
			(layer "F.Fab")
			(hide yes)
			(effects
				(font
					(size 1.016 1.016)
					(thickness 0.1524)
				)
			)
		)
		(duplicate_pad_numbers_are_jumpers no)
		(fp_line
			(start -0.508 -0.9398)
			(end -0.508 0.9398)
			(stroke
				(width 0.1524)
				(type default)
			)
			(layer "F.SilkS")
		)
		(fp_line
			(start 0.508 -0.9398)
			(end -0.508 -0.9398)
			(stroke
				(width 0.1524)
				(type default)
			)
			(layer "F.SilkS")
		)
		(fp_rect
			(start -0.508 0.9398)
			(end 0.508 -0.9398)
			(stroke
				(width 0)
				(type default)
			)
			(fill no)
			(layer "F.CrtYd")
		)
		(fp_rect
			(start -0.508 0.9398)
			(end 0.508 -0.9398)
			(stroke
				(width 0)
				(type default)
			)
			(fill no)
			(layer "F.Fab")
		)
		(pad "1" smd custom
			(at 0 -0.4445 270)
			(size 0.1397 0.1397)
			(layers "F.Cu" "F.Mask" "F.Paste")
			(net "SDA_DR2_R")
			(options
				(clearance outline)
				(anchor circle)
			)
			(primitives
				(gr_poly
					(pts
						(arc
							(start -0.1778 -0.2794)
							(mid -0.249642 -0.249642)
							(end -0.2794 -0.1778)
						)
						(arc
							(start -0.2794 0.1778)
							(mid -0.249642 0.249642)
							(end -0.1778 0.2794)
						)
						(arc
							(start 0.1778 0.2794)
							(mid 0.249642 0.249642)
							(end 0.2794 0.1778)
						)
						(arc
							(start 0.2794 -0.1778)
							(mid 0.249642 -0.249642)
							(end 0.1778 -0.2794)
						)
					)
					(width 0)
					(fill yes)
				)
			)
		)
		(pad "2" smd custom
			(at 0 0.4445 270)
			(size 0.1397 0.1397)
			(layers "F.Cu" "F.Mask" "F.Paste")
			(net "SDA_DR2")
			(options
				(clearance outline)
				(anchor circle)
			)
			(primitives
				(gr_poly
					(pts
						(arc
							(start -0.1778 -0.2794)
							(mid -0.249642 -0.249642)
							(end -0.2794 -0.1778)
						)
						(arc
							(start -0.2794 0.1778)
							(mid -0.249642 0.249642)
							(end -0.1778 0.2794)
						)
						(arc
							(start 0.1778 0.2794)
							(mid 0.249642 0.249642)
							(end 0.2794 0.1778)
						)
						(arc
							(start 0.2794 -0.1778)
							(mid 0.249642 -0.249642)
							(end 0.1778 -0.2794)
						)
					)
					(width 0)
					(fill yes)
				)
			)
		)
	)
	(footprint ""
		(layer "F.Cu")
		(at 22.86 -94.234 180)
		(property "Reference" "R9750"
			(at 0 0 180)
			(layer "F.SilkS")
			(hide yes)
			(effects
				(font
					(size 1.27 1.27)
				)
			)
		)
		(property "Value" "4K7R2J-2-GP"
			(at 0.064008 -3.993896 180)
			(unlocked yes)
			(layer "F.Fab")
			(hide yes)
			(effects
				(font
					(size 1.016 1.016)
					(thickness 0.1524)
				)
			)
		)
		(property "Device Type" "R402H16"
			(at 0.064008 -5.517896 180)
			(unlocked yes)
			(layer "F.Fab")
			(hide yes)
			(effects
				(font
					(size 1.016 1.016)
					(thickness 0.1524)
				)
			)
		)
		(duplicate_pad_numbers_are_jumpers no)
		(fp_line
			(start 0.508 -0.9398)
			(end -0.508 -0.9398)
			(stroke
				(width 0.1524)
				(type default)
			)
			(layer "F.SilkS")
		)
		(fp_line
			(start -0.508 -0.9398)
			(end -0.508 0.9398)
			(stroke
				(width 0.1524)
				(type default)
			)
			(layer "F.SilkS")
		)
		(fp_rect
			(start -0.508 0.9398)
			(end 0.508 -0.9398)
			(stroke
				(width 0)
				(type default)
			)
			(fill no)
			(layer "F.CrtYd")
		)
		(fp_rect
			(start -0.508 0.9398)
			(end 0.508 -0.9398)
			(stroke
				(width 0)
				(type default)
			)
			(fill no)
			(layer "F.Fab")
		)
		(pad "1" smd custom
			(at 0 -0.4445 180)
			(size 0.1397 0.1397)
			(layers "F.Cu" "F.Mask" "F.Paste")
			(net "P3V3")
			(options
				(clearance outline)
				(anchor circle)
			)
			(primitives
				(gr_poly
					(pts
						(arc
							(start -0.1778 -0.2794)
							(mid -0.249642 -0.249642)
							(end -0.2794 -0.1778)
						)
						(arc
							(start -0.2794 0.1778)
							(mid -0.249642 0.249642)
							(end -0.1778 0.2794)
						)
						(arc
							(start 0.1778 0.2794)
							(mid 0.249642 0.249642)
							(end 0.2794 0.1778)
						)
						(arc
							(start 0.2794 -0.1778)
							(mid 0.249642 -0.249642)
							(end 0.1778 -0.2794)
						)
					)
					(width 0)
					(fill yes)
				)
			)
		)
		(pad "2" smd custom
			(at 0 0.4445 180)
			(size 0.1397 0.1397)
			(layers "F.Cu" "F.Mask" "F.Paste")
			(net "SSD9_PWREN")
			(options
				(clearance outline)
				(anchor circle)
			)
			(primitives
				(gr_poly
					(pts
						(arc
							(start -0.1778 -0.2794)
							(mid -0.249642 -0.249642)
							(end -0.2794 -0.1778)
						)
						(arc
							(start -0.2794 0.1778)
							(mid -0.249642 0.249642)
							(end -0.1778 0.2794)
						)
						(arc
							(start 0.1778 0.2794)
							(mid 0.249642 0.249642)
							(end 0.2794 0.1778)
						)
						(arc
							(start 0.2794 -0.1778)
							(mid 0.249642 -0.249642)
							(end 0.1778 -0.2794)
						)
					)
					(width 0)
					(fill yes)
				)
			)
		)
	)
	(footprint ""
		(layer "F.Cu")
		(at 87.503 -423.164)
		(property "Reference" "R9072"
			(at 0 0 0)
			(layer "F.SilkS")
			(hide yes)
			(effects
				(font
					(size 1.27 1.27)
				)
			)
		)
		(property "Value" "27R2F-GP"
			(at 0.064008 -3.993896 0)
			(unlocked yes)
			(layer "F.Fab")
			(hide yes)
			(effects
				(font
					(size 1.016 1.016)
					(thickness 0.1524)
				)
			)
		)
		(property "Device Type" "R402H16"
			(at 0.064008 -5.517896 0)
			(unlocked yes)
			(layer "F.Fab")
			(hide yes)
			(effects
				(font
					(size 1.016 1.016)
					(thickness 0.1524)
				)
			)
		)
		(duplicate_pad_numbers_are_jumpers no)
		(fp_line
			(start -0.508 -0.9398)
			(end -0.508 0.9398)
			(stroke
				(width 0.1524)
				(type default)
			)
			(layer "F.SilkS")
		)
		(fp_line
			(start 0.508 -0.9398)
			(end -0.508 -0.9398)
			(stroke
				(width 0.1524)
				(type default)
			)
			(layer "F.SilkS")
		)
		(fp_rect
			(start -0.508 0.9398)
			(end 0.508 -0.9398)
			(stroke
				(width 0)
				(type default)
			)
			(fill no)
			(layer "F.CrtYd")
		)
		(fp_rect
			(start -0.508 0.9398)
			(end 0.508 -0.9398)
			(stroke
				(width 0)
				(type default)
			)
			(fill no)
			(layer "F.Fab")
		)
		(pad "1" smd custom
			(at 0 -0.4445)
			(size 0.1397 0.1397)
			(layers "F.Cu" "F.Mask" "F.Paste")
			(net "PE_CLK_100M_DR10_2_R_N")
			(options
				(clearance outline)
				(anchor circle)
			)
			(primitives
				(gr_poly
					(pts
						(arc
							(start -0.1778 -0.2794)
							(mid -0.249642 -0.249642)
							(end -0.2794 -0.1778)
						)
						(arc
							(start -0.2794 0.1778)
							(mid -0.249642 0.249642)
							(end -0.1778 0.2794)
						)
						(arc
							(start 0.1778 0.2794)
							(mid 0.249642 0.249642)
							(end 0.2794 0.1778)
						)
						(arc
							(start 0.2794 -0.1778)
							(mid 0.249642 -0.249642)
							(end 0.1778 -0.2794)
						)
					)
					(width 0)
					(fill yes)
				)
			)
		)
		(pad "2" smd custom
			(at 0 0.4445)
			(size 0.1397 0.1397)
			(layers "F.Cu" "F.Mask" "F.Paste")
			(net "PE_CLK100M_DR10_2_N")
			(options
				(clearance outline)
				(anchor circle)
			)
			(primitives
				(gr_poly
					(pts
						(arc
							(start -0.1778 -0.2794)
							(mid -0.249642 -0.249642)
							(end -0.2794 -0.1778)
						)
						(arc
							(start -0.2794 0.1778)
							(mid -0.249642 0.249642)
							(end -0.1778 0.2794)
						)
						(arc
							(start 0.1778 0.2794)
							(mid 0.249642 0.249642)
							(end 0.2794 0.1778)
						)
						(arc
							(start 0.2794 -0.1778)
							(mid 0.249642 -0.249642)
							(end 0.1778 -0.2794)
						)
					)
					(width 0)
					(fill yes)
				)
			)
		)
	)
	(footprint ""
		(layer "F.Cu")
		(at 227.457 -34.913062 90)
		(property "Reference" "U201"
			(at 0 0 90)
			(layer "F.SilkS")
			(hide yes)
			(effects
				(font
					(size 1.27 1.27)
				)
			)
		)
		(property "Value" "SN74LVC1G08DCKR-GP"
			(at -2.3368 -8.6868 90)
			(unlocked yes)
			(layer "F.Fab")
			(hide yes)
			(effects
				(font
					(size 1.016 1.016)
					(thickness 0.1524)
				)
			)
		)
		(property "Device Type" "SC70-5H44"
			(at -2.3114 -10.414 90)
			(unlocked yes)
			(layer "F.Fab")
			(hide yes)
			(effects
				(font
					(size 1.016 1.016)
					(thickness 0.1524)
				)
			)
		)
		(duplicate_pad_numbers_are_jumpers no)
		(fp_line
			(start 1.3843 -1.8034)
			(end 1.3843 -1.1176)
			(stroke
				(width 0.3302)
				(type default)
			)
			(layer "F.SilkS")
		)
		(fp_line
			(start 0.6604 -1.8034)
			(end 1.3843 -1.8034)
			(stroke
				(width 0.3302)
				(type default)
			)
			(layer "F.SilkS")
		)
		(fp_line
			(start 1.27 -1.7018)
			(end 1.27 1.7018)
			(stroke
				(width 0.1524)
				(type default)
			)
			(layer "F.SilkS")
		)
		(fp_line
			(start -1.27 -1.7018)
			(end 1.27 -1.7018)
			(stroke
				(width 0.1524)
				(type default)
			)
			(layer "F.SilkS")
		)
		(fp_line
			(start 1.27 1.7018)
			(end -1.27 1.7018)
			(stroke
				(width 0.1524)
				(type default)
			)
			(layer "F.SilkS")
		)
		(fp_line
			(start -1.27 1.7018)
			(end -1.27 -1.7018)
			(stroke
				(width 0.1524)
				(type default)
			)
			(layer "F.SilkS")
		)
		(fp_rect
			(start -1.524 1.9558)
			(end 1.524 -1.9558)
			(stroke
				(width 0)
				(type default)
			)
			(fill no)
			(layer "F.CrtYd")
		)
		(fp_poly
			(pts
				(xy -1.524 -1.9558) (xy 1.524 -1.9558) (xy 1.524 1.9558) (xy -1.524 1.9558)
			)
			(stroke
				(width 0)
				(type default)
			)
			(fill no)
			(layer "F.Fab")
		)
		(pad "1" smd rect
			(at 0.65024 -0.8255 90)
			(size 0.4064 1.2192)
			(layers "F.Cu" "F.Mask" "F.Paste")
			(net "SSD4_CLK0_OE_MOS_N")
		)
		(pad "2" smd rect
			(at 0 -0.8255 90)
			(size 0.4064 1.2192)
			(layers "F.Cu" "F.Mask" "F.Paste")
			(net "ATTN_LED_DR4_N")
		)
		(pad "3" smd rect
			(at -0.65024 -0.8255 90)
			(size 0.4064 1.2192)
			(layers "F.Cu" "F.Mask" "F.Paste")
			(net "GND")
		)
		(pad "4" smd rect
			(at -0.65024 0.8255 90)
			(size 0.4064 1.2192)
			(layers "F.Cu" "F.Mask" "F.Paste")
			(net "ATTN_LED_DR4_AND")
		)
		(pad "5" smd rect
			(at 0.65024 0.8255 90)
			(size 0.4064 1.2192)
			(layers "F.Cu" "F.Mask" "F.Paste")
			(net "P3V3")
		)
	)
	(footprint ""
		(layer "F.Cu")
		(at 96.647 -88.138 180)
		(property "Reference" "R9616"
			(at 0 0 180)
			(layer "F.SilkS")
			(hide yes)
			(effects
				(font
					(size 1.27 1.27)
				)
			)
		)
		(property "Value" "10R2F-L-GP"
			(at 0.064008 -3.993896 180)
			(unlocked yes)
			(layer "F.Fab")
			(hide yes)
			(effects
				(font
					(size 1.016 1.016)
					(thickness 0.1524)
				)
			)
		)
		(property "Device Type" "R402H14"
			(at 0.064008 -5.517896 180)
			(unlocked yes)
			(layer "F.Fab")
			(hide yes)
			(effects
				(font
					(size 1.016 1.016)
					(thickness 0.1524)
				)
			)
		)
		(duplicate_pad_numbers_are_jumpers no)
		(fp_line
			(start 0.508 -0.9398)
			(end -0.508 -0.9398)
			(stroke
				(width 0.1524)
				(type default)
			)
			(layer "F.SilkS")
		)
		(fp_line
			(start -0.508 -0.9398)
			(end -0.508 0.9398)
			(stroke
				(width 0.1524)
				(type default)
			)
			(layer "F.SilkS")
		)
		(fp_rect
			(start -0.508 0.9398)
			(end 0.508 -0.9398)
			(stroke
				(width 0)
				(type default)
			)
			(fill no)
			(layer "F.CrtYd")
		)
		(fp_rect
			(start -0.508 0.9398)
			(end 0.508 -0.9398)
			(stroke
				(width 0)
				(type default)
			)
			(fill no)
			(layer "F.Fab")
		)
		(pad "1" smd custom
			(at 0 -0.4445 180)
			(size 0.1397 0.1397)
			(layers "F.Cu" "F.Mask" "F.Paste")
			(net "SSD_PRSNT_NET14")
			(options
				(clearance outline)
				(anchor circle)
			)
			(primitives
				(gr_poly
					(pts
						(arc
							(start -0.1778 -0.2794)
							(mid -0.249642 -0.249642)
							(end -0.2794 -0.1778)
						)
						(arc
							(start -0.2794 0.1778)
							(mid -0.249642 0.249642)
							(end -0.1778 0.2794)
						)
						(arc
							(start 0.1778 0.2794)
							(mid 0.249642 0.249642)
							(end 0.2794 0.1778)
						)
						(arc
							(start 0.2794 -0.1778)
							(mid 0.249642 -0.249642)
							(end 0.1778 -0.2794)
						)
					)
					(width 0)
					(fill yes)
				)
			)
		)
		(pad "2" smd custom
			(at 0 0.4445 180)
			(size 0.1397 0.1397)
			(layers "F.Cu" "F.Mask" "F.Paste")
			(net "SSD_PRSNT14")
			(options
				(clearance outline)
				(anchor circle)
			)
			(primitives
				(gr_poly
					(pts
						(arc
							(start -0.1778 -0.2794)
							(mid -0.249642 -0.249642)
							(end -0.2794 -0.1778)
						)
						(arc
							(start -0.2794 0.1778)
							(mid -0.249642 0.249642)
							(end -0.1778 0.2794)
						)
						(arc
							(start 0.1778 0.2794)
							(mid 0.249642 0.249642)
							(end 0.2794 0.1778)
						)
						(arc
							(start 0.2794 -0.1778)
							(mid 0.249642 -0.249642)
							(end 0.1778 -0.2794)
						)
					)
					(width 0)
					(fill yes)
				)
			)
		)
	)
	(footprint ""
		(layer "F.Cu")
		(at 29.845 -321.437 90)
		(property "Reference" "R410"
			(at 0 0 90)
			(layer "F.SilkS")
			(hide yes)
			(effects
				(font
					(size 1.27 1.27)
				)
			)
		)
		(property "Value" "0R2J-2-GP"
			(at 0.064008 -3.993896 90)
			(unlocked yes)
			(layer "F.Fab")
			(hide yes)
			(effects
				(font
					(size 1.016 1.016)
					(thickness 0.1524)
				)
			)
		)
		(property "Device Type" "R402H16"
			(at 0.064008 -5.517896 90)
			(unlocked yes)
			(layer "F.Fab")
			(hide yes)
			(effects
				(font
					(size 1.016 1.016)
					(thickness 0.1524)
				)
			)
		)
		(duplicate_pad_numbers_are_jumpers no)
		(fp_line
			(start 0.508 -0.9398)
			(end -0.508 -0.9398)
			(stroke
				(width 0.1524)
				(type default)
			)
			(layer "F.SilkS")
		)
		(fp_line
			(start -0.508 -0.9398)
			(end -0.508 0.9398)
			(stroke
				(width 0.1524)
				(type default)
			)
			(layer "F.SilkS")
		)
		(fp_rect
			(start -0.508 0.9398)
			(end 0.508 -0.9398)
			(stroke
				(width 0)
				(type default)
			)
			(fill no)
			(layer "F.CrtYd")
		)
		(fp_rect
			(start -0.508 0.9398)
			(end 0.508 -0.9398)
			(stroke
				(width 0)
				(type default)
			)
			(fill no)
			(layer "F.Fab")
		)
		(pad "1" smd custom
			(at 0 -0.4445 90)
			(size 0.1397 0.1397)
			(layers "F.Cu" "F.Mask" "F.Paste")
			(net "SCL_DR11_R")
			(options
				(clearance outline)
				(anchor circle)
			)
			(primitives
				(gr_poly
					(pts
						(arc
							(start -0.1778 -0.2794)
							(mid -0.249642 -0.249642)
							(end -0.2794 -0.1778)
						)
						(arc
							(start -0.2794 0.1778)
							(mid -0.249642 0.249642)
							(end -0.1778 0.2794)
						)
						(arc
							(start 0.1778 0.2794)
							(mid 0.249642 0.249642)
							(end 0.2794 0.1778)
						)
						(arc
							(start 0.2794 -0.1778)
							(mid 0.249642 -0.249642)
							(end 0.1778 -0.2794)
						)
					)
					(width 0)
					(fill yes)
				)
			)
		)
		(pad "2" smd custom
			(at 0 0.4445 90)
			(size 0.1397 0.1397)
			(layers "F.Cu" "F.Mask" "F.Paste")
			(net "SCL_DR11")
			(options
				(clearance outline)
				(anchor circle)
			)
			(primitives
				(gr_poly
					(pts
						(arc
							(start -0.1778 -0.2794)
							(mid -0.249642 -0.249642)
							(end -0.2794 -0.1778)
						)
						(arc
							(start -0.2794 0.1778)
							(mid -0.249642 0.249642)
							(end -0.1778 0.2794)
						)
						(arc
							(start 0.1778 0.2794)
							(mid 0.249642 0.249642)
							(end 0.2794 0.1778)
						)
						(arc
							(start 0.2794 -0.1778)
							(mid 0.249642 -0.249642)
							(end 0.1778 -0.2794)
						)
					)
					(width 0)
					(fill yes)
				)
			)
		)
	)
	(footprint ""
		(layer "F.Cu")
		(at 70.739 -143.51 90)
		(property "Reference" "SR967"
			(at 0 0 90)
			(layer "F.SilkS")
			(hide yes)
			(effects
				(font
					(size 1.27 1.27)
				)
			)
		)
		(property "Value" "2KR2F-3-GP"
			(at 0.064008 -3.993896 90)
			(unlocked yes)
			(layer "F.Fab")
			(hide yes)
			(effects
				(font
					(size 1.016 1.016)
					(thickness 0.1524)
				)
			)
		)
		(property "Device Type" "R402H16"
			(at 0.064008 -5.517896 90)
			(unlocked yes)
			(layer "F.Fab")
			(hide yes)
			(effects
				(font
					(size 1.016 1.016)
					(thickness 0.1524)
				)
			)
		)
		(duplicate_pad_numbers_are_jumpers no)
		(fp_line
			(start 0.508 -0.9398)
			(end -0.508 -0.9398)
			(stroke
				(width 0.1524)
				(type default)
			)
			(layer "F.SilkS")
		)
		(fp_line
			(start -0.508 -0.9398)
			(end -0.508 0.9398)
			(stroke
				(width 0.1524)
				(type default)
			)
			(layer "F.SilkS")
		)
		(fp_rect
			(start -0.508 0.9398)
			(end 0.508 -0.9398)
			(stroke
				(width 0)
				(type default)
			)
			(fill no)
			(layer "F.CrtYd")
		)
		(fp_rect
			(start -0.508 0.9398)
			(end 0.508 -0.9398)
			(stroke
				(width 0)
				(type default)
			)
			(fill no)
			(layer "F.Fab")
		)
		(pad "1" smd custom
			(at 0 -0.4445 90)
			(size 0.1397 0.1397)
			(layers "F.Cu" "F.Mask" "F.Paste")
			(net "P3V3")
			(options
				(clearance outline)
				(anchor circle)
			)
			(primitives
				(gr_poly
					(pts
						(arc
							(start -0.1778 -0.2794)
							(mid -0.249642 -0.249642)
							(end -0.2794 -0.1778)
						)
						(arc
							(start -0.2794 0.1778)
							(mid -0.249642 0.249642)
							(end -0.1778 0.2794)
						)
						(arc
							(start 0.1778 0.2794)
							(mid 0.249642 0.249642)
							(end 0.2794 0.1778)
						)
						(arc
							(start 0.2794 -0.1778)
							(mid 0.249642 -0.249642)
							(end 0.1778 -0.2794)
						)
					)
					(width 0)
					(fill yes)
				)
			)
		)
		(pad "2" smd custom
			(at 0 0.4445 90)
			(size 0.1397 0.1397)
			(layers "F.Cu" "F.Mask" "F.Paste")
			(net "SCL_DR9")
			(options
				(clearance outline)
				(anchor circle)
			)
			(primitives
				(gr_poly
					(pts
						(arc
							(start -0.1778 -0.2794)
							(mid -0.249642 -0.249642)
							(end -0.2794 -0.1778)
						)
						(arc
							(start -0.2794 0.1778)
							(mid -0.249642 0.249642)
							(end -0.1778 0.2794)
						)
						(arc
							(start 0.1778 0.2794)
							(mid 0.249642 0.249642)
							(end 0.2794 0.1778)
						)
						(arc
							(start 0.2794 -0.1778)
							(mid 0.249642 -0.249642)
							(end 0.1778 -0.2794)
						)
					)
					(width 0)
					(fill yes)
				)
			)
		)
	)
)
